(kicad_pcb
	(version 20260206)
	(generator "pcbnew")
	(generator_version "10.0")
	(general
		(thickness 1.6)
		(legacy_teardrops no)
	)
	(paper "A4")
	(title_block
		(title "12092022_DA0F0TFB6D0_F0T_FAN_BOARD_MP5048_D_brd_v02_OCP.brd")
		(comment 1 "Grand Teton / footprints 250-255 of 924")
	)
	(layers
		(0 "F.Cu" signal "TOP")
		(4 "In1.Cu" signal "GND")
		(6 "In2.Cu" signal "IN1")
		(8 "In3.Cu" signal "IN2")
		(10 "In4.Cu" signal "GND1")
		(2 "B.Cu" signal "BOTTOM")
		(9 "F.Adhes" user "F.Adhesive")
		(11 "B.Adhes" user "B.Adhesive")
		(13 "F.Paste" user "Package Geometry/Pastemask Top")
		(15 "B.Paste" user "Package Geometry/Pastemask Bottom")
		(5 "F.SilkS" user "Ref Des/Silkscreen Top")
		(7 "B.SilkS" user "Ref Des/Silkscreen Bottom")
		(1 "F.Mask" user "Board Geometry/Soldermask Top")
		(3 "B.Mask" user "Board Geometry/Soldermask Bottom")
		(17 "Dwgs.User" user "User.Drawings")
		(19 "Cmts.User" user "User.Comments")
		(21 "Eco1.User" user "User.Eco1")
		(23 "Eco2.User" user "User.Eco2")
		(25 "Edge.Cuts" user "Board Geometry/Outline")
		(27 "Margin" user)
		(31 "F.CrtYd" user "Package Geometry/Place Bound Top")
		(29 "B.CrtYd" user "Package Geometry/Place Bound Bottom")
		(35 "F.Fab" user "Ref Des/Assembly Top")
		(33 "B.Fab" user "Ref Des/Assembly Bottom")
	)
	(footprint ""
		(layer "F.Cu")
		(at 3.429 -124.714 180)
		(property "Reference" "C2027"
			(at 0 0 180)
			(layer "F.SilkS")
			(hide yes)
			(effects
				(font
					(size 1.27 1.27)
				)
			)
		)
		(property "Value" ""
			(at 0 0 180)
			(layer "F.Fab")
			(effects
				(font
					(size 1.27 1.27)
				)
			)
		)
		(duplicate_pad_numbers_are_jumpers no)
		(fp_line
			(start 0.7874 0.4064)
			(end -0.7874 0.4064)
			(stroke
				(width 0.1524)
				(type default)
			)
			(layer "F.SilkS")
		)
		(fp_line
			(start 0.7874 -0.4064)
			(end 0.7874 0.4064)
			(stroke
				(width 0.1524)
				(type default)
			)
			(layer "F.SilkS")
		)
		(fp_line
			(start -0.7874 0.4064)
			(end -0.7874 -0.4064)
			(stroke
				(width 0.1524)
				(type default)
			)
			(layer "F.SilkS")
		)
		(fp_line
			(start -0.7874 -0.4064)
			(end 0.7874 -0.4064)
			(stroke
				(width 0.1524)
				(type default)
			)
			(layer "F.SilkS")
		)
		(fp_line
			(start 0.6858 0.3048)
			(end 0.1016 0.3048)
			(stroke
				(width 0.1)
				(type default)
			)
			(layer "F.Fab")
		)
		(fp_line
			(start 0.6858 -0.3048)
			(end 0.6858 0.3048)
			(stroke
				(width 0.1)
				(type default)
			)
			(layer "F.Fab")
		)
		(fp_line
			(start 0.1016 0.3048)
			(end 0.1016 0.2794)
			(stroke
				(width 0.1)
				(type default)
			)
			(layer "F.Fab")
		)
		(fp_line
			(start 0.1016 0.2794)
			(end -0.1016 0.2794)
			(stroke
				(width 0.1)
				(type default)
			)
			(layer "F.Fab")
		)
		(fp_line
			(start 0.1016 -0.2794)
			(end 0.1016 -0.3048)
			(stroke
				(width 0.1)
				(type default)
			)
			(layer "F.Fab")
		)
		(fp_line
			(start 0.1016 -0.3048)
			(end 0.6858 -0.3048)
			(stroke
				(width 0.1)
				(type default)
			)
			(layer "F.Fab")
		)
		(fp_line
			(start -0.1016 0.3048)
			(end -0.6858 0.3048)
			(stroke
				(width 0.1)
				(type default)
			)
			(layer "F.Fab")
		)
		(fp_line
			(start -0.1016 0.2794)
			(end -0.1016 0.3048)
			(stroke
				(width 0.1)
				(type default)
			)
			(layer "F.Fab")
		)
		(fp_line
			(start -0.1016 -0.2794)
			(end 0.1016 -0.2794)
			(stroke
				(width 0.1)
				(type default)
			)
			(layer "F.Fab")
		)
		(fp_line
			(start -0.1016 -0.3048)
			(end -0.1016 -0.2794)
			(stroke
				(width 0.1)
				(type default)
			)
			(layer "F.Fab")
		)
		(fp_line
			(start -0.6858 0.3048)
			(end -0.6858 -0.3048)
			(stroke
				(width 0.1)
				(type default)
			)
			(layer "F.Fab")
		)
		(fp_line
			(start -0.6858 -0.3048)
			(end -0.1016 -0.3048)
			(stroke
				(width 0.1)
				(type default)
			)
			(layer "F.Fab")
		)
		(pad "1" smd rect
			(at -0.40005 0)
			(size 0.4572 0.508)
			(layers "F.Cu" "F.Mask" "F.Paste")
			(net "GND")
		)
		(pad "2" smd rect
			(at 0.40005 0)
			(size 0.4572 0.508)
			(layers "F.Cu" "F.Mask" "F.Paste")
			(net "P12V_LED_FAN5")
		)
	)
	(footprint ""
		(layer "F.Cu")
		(at 34.666428 -252.894846 90)
		(property "Reference" "C2067"
			(at 0 0 90)
			(layer "F.SilkS")
			(hide yes)
			(effects
				(font
					(size 1.27 1.27)
				)
			)
		)
		(property "Value" ""
			(at 0 0 90)
			(layer "F.Fab")
			(effects
				(font
					(size 1.27 1.27)
				)
			)
		)
		(duplicate_pad_numbers_are_jumpers no)
		(fp_line
			(start 0.7874 -0.4064)
			(end 0.7874 0.4064)
			(stroke
				(width 0.1524)
				(type default)
			)
			(layer "F.SilkS")
		)
		(fp_line
			(start -0.7874 -0.4064)
			(end 0.7874 -0.4064)
			(stroke
				(width 0.1524)
				(type default)
			)
			(layer "F.SilkS")
		)
		(fp_line
			(start 0.7874 0.4064)
			(end -0.7874 0.4064)
			(stroke
				(width 0.1524)
				(type default)
			)
			(layer "F.SilkS")
		)
		(fp_line
			(start -0.7874 0.4064)
			(end -0.7874 -0.4064)
			(stroke
				(width 0.1524)
				(type default)
			)
			(layer "F.SilkS")
		)
		(fp_line
			(start -0.12065 -0.305054)
			(end -0.12065 -0.2794)
			(stroke
				(width 0.1)
				(type default)
			)
			(layer "F.Fab")
		)
		(fp_line
			(start -0.67945 -0.305054)
			(end -0.12065 -0.305054)
			(stroke
				(width 0.1)
				(type default)
			)
			(layer "F.Fab")
		)
		(fp_line
			(start 0.67945 -0.3048)
			(end 0.67945 0.3048)
			(stroke
				(width 0.1)
				(type default)
			)
			(layer "F.Fab")
		)
		(fp_line
			(start 0.12065 -0.3048)
			(end 0.67945 -0.3048)
			(stroke
				(width 0.1)
				(type default)
			)
			(layer "F.Fab")
		)
		(fp_line
			(start 0.12065 -0.2794)
			(end 0.12065 -0.3048)
			(stroke
				(width 0.1)
				(type default)
			)
			(layer "F.Fab")
		)
		(fp_line
			(start -0.12065 -0.2794)
			(end 0.12065 -0.2794)
			(stroke
				(width 0.1)
				(type default)
			)
			(layer "F.Fab")
		)
		(fp_line
			(start 0.120396 0.2794)
			(end -0.12065 0.2794)
			(stroke
				(width 0.1)
				(type default)
			)
			(layer "F.Fab")
		)
		(fp_line
			(start -0.12065 0.2794)
			(end -0.12065 0.3048)
			(stroke
				(width 0.1)
				(type default)
			)
			(layer "F.Fab")
		)
		(fp_line
			(start 0.67945 0.3048)
			(end 0.120396 0.3048)
			(stroke
				(width 0.1)
				(type default)
			)
			(layer "F.Fab")
		)
		(fp_line
			(start 0.120396 0.3048)
			(end 0.120396 0.2794)
			(stroke
				(width 0.1)
				(type default)
			)
			(layer "F.Fab")
		)
		(fp_line
			(start -0.12065 0.3048)
			(end -0.67945 0.3048)
			(stroke
				(width 0.1)
				(type default)
			)
			(layer "F.Fab")
		)
		(fp_line
			(start -0.67945 0.3048)
			(end -0.67945 -0.305054)
			(stroke
				(width 0.1)
				(type default)
			)
			(layer "F.Fab")
		)
		(pad "1" smd circle
			(at -0.40005 0 90)
			(size 0 0)
			(layers "F.Cu" "F.Mask" "F.Paste")
			(net "P3V3_AUX")
		)
		(pad "2" smd circle
			(at 0.40005 0 90)
			(size 0 0)
			(layers "F.Cu" "F.Mask" "F.Paste")
			(net "GND")
		)
	)
	(footprint ""
		(layer "F.Cu")
		(at 35.052 -107.823)
		(property "Reference" "R5529"
			(at 0 0 0)
			(layer "F.SilkS")
			(hide yes)
			(effects
				(font
					(size 1.27 1.27)
				)
			)
		)
		(property "Value" ""
			(at 0 0 0)
			(layer "F.Fab")
			(effects
				(font
					(size 1.27 1.27)
				)
			)
		)
		(duplicate_pad_numbers_are_jumpers no)
		(fp_line
			(start -0.7874 -0.4064)
			(end 0.7874 -0.4064)
			(stroke
				(width 0.1524)
				(type default)
			)
			(layer "F.SilkS")
		)
		(fp_line
			(start -0.7874 0.4064)
			(end -0.7874 -0.4064)
			(stroke
				(width 0.1524)
				(type default)
			)
			(layer "F.SilkS")
		)
		(fp_line
			(start 0.7874 -0.4064)
			(end 0.7874 0.4064)
			(stroke
				(width 0.1524)
				(type default)
			)
			(layer "F.SilkS")
		)
		(fp_line
			(start 0.7874 0.4064)
			(end -0.7874 0.4064)
			(stroke
				(width 0.1524)
				(type default)
			)
			(layer "F.SilkS")
		)
		(fp_line
			(start -0.67945 -0.305054)
			(end -0.12065 -0.305054)
			(stroke
				(width 0.1)
				(type default)
			)
			(layer "F.Fab")
		)
		(fp_line
			(start -0.67945 0.3048)
			(end -0.67945 -0.305054)
			(stroke
				(width 0.1)
				(type default)
			)
			(layer "F.Fab")
		)
		(fp_line
			(start -0.12065 -0.305054)
			(end -0.12065 -0.2794)
			(stroke
				(width 0.1)
				(type default)
			)
			(layer "F.Fab")
		)
		(fp_line
			(start -0.12065 -0.2794)
			(end 0.12065 -0.2794)
			(stroke
				(width 0.1)
				(type default)
			)
			(layer "F.Fab")
		)
		(fp_line
			(start -0.12065 0.2794)
			(end -0.12065 0.3048)
			(stroke
				(width 0.1)
				(type default)
			)
			(layer "F.Fab")
		)
		(fp_line
			(start -0.12065 0.3048)
			(end -0.67945 0.3048)
			(stroke
				(width 0.1)
				(type default)
			)
			(layer "F.Fab")
		)
		(fp_line
			(start 0.120396 0.2794)
			(end -0.12065 0.2794)
			(stroke
				(width 0.1)
				(type default)
			)
			(layer "F.Fab")
		)
		(fp_line
			(start 0.120396 0.3048)
			(end 0.120396 0.2794)
			(stroke
				(width 0.1)
				(type default)
			)
			(layer "F.Fab")
		)
		(fp_line
			(start 0.12065 -0.3048)
			(end 0.67945 -0.3048)
			(stroke
				(width 0.1)
				(type default)
			)
			(layer "F.Fab")
		)
		(fp_line
			(start 0.12065 -0.2794)
			(end 0.12065 -0.3048)
			(stroke
				(width 0.1)
				(type default)
			)
			(layer "F.Fab")
		)
		(fp_line
			(start 0.67945 -0.3048)
			(end 0.67945 0.3048)
			(stroke
				(width 0.1)
				(type default)
			)
			(layer "F.Fab")
		)
		(fp_line
			(start 0.67945 0.3048)
			(end 0.120396 0.3048)
			(stroke
				(width 0.1)
				(type default)
			)
			(layer "F.Fab")
		)
		(pad "1" smd rect
			(at -0.40005 0 180)
			(size 0.4572 0.508)
			(layers "F.Cu" "F.Mask" "F.Paste")
			(net "P12V_LED_FAN2")
		)
		(pad "2" smd rect
			(at 0.40005 0 180)
			(size 0.4572 0.508)
			(layers "F.Cu" "F.Mask" "F.Paste")
			(net "FAN_2_OK_LED_R_N")
		)
	)
	(footprint ""
		(layer "F.Cu")
		(at 20.32 -141.605 -90)
		(property "Reference" "R572"
			(at 0 0 270)
			(layer "F.SilkS")
			(hide yes)
			(effects
				(font
					(size 1.27 1.27)
				)
			)
		)
		(property "Value" ""
			(at 0 0 270)
			(layer "F.Fab")
			(effects
				(font
					(size 1.27 1.27)
				)
			)
		)
		(duplicate_pad_numbers_are_jumpers no)
		(fp_line
			(start -0.7874 0.4064)
			(end -0.7874 -0.4064)
			(stroke
				(width 0.1524)
				(type default)
			)
			(layer "F.SilkS")
		)
		(fp_line
			(start 0.7874 0.4064)
			(end -0.7874 0.4064)
			(stroke
				(width 0.1524)
				(type default)
			)
			(layer "F.SilkS")
		)
		(fp_line
			(start -0.7874 -0.4064)
			(end 0.7874 -0.4064)
			(stroke
				(width 0.1524)
				(type default)
			)
			(layer "F.SilkS")
		)
		(fp_line
			(start 0.7874 -0.4064)
			(end 0.7874 0.4064)
			(stroke
				(width 0.1524)
				(type default)
			)
			(layer "F.SilkS")
		)
		(fp_line
			(start -0.67945 0.3048)
			(end -0.67945 -0.305054)
			(stroke
				(width 0.1)
				(type default)
			)
			(layer "F.Fab")
		)
		(fp_line
			(start -0.12065 0.3048)
			(end -0.67945 0.3048)
			(stroke
				(width 0.1)
				(type default)
			)
			(layer "F.Fab")
		)
		(fp_line
			(start 0.120396 0.3048)
			(end 0.120396 0.2794)
			(stroke
				(width 0.1)
				(type default)
			)
			(layer "F.Fab")
		)
		(fp_line
			(start 0.67945 0.3048)
			(end 0.120396 0.3048)
			(stroke
				(width 0.1)
				(type default)
			)
			(layer "F.Fab")
		)
		(fp_line
			(start -0.12065 0.2794)
			(end -0.12065 0.3048)
			(stroke
				(width 0.1)
				(type default)
			)
			(layer "F.Fab")
		)
		(fp_line
			(start 0.120396 0.2794)
			(end -0.12065 0.2794)
			(stroke
				(width 0.1)
				(type default)
			)
			(layer "F.Fab")
		)
		(fp_line
			(start -0.12065 -0.2794)
			(end 0.12065 -0.2794)
			(stroke
				(width 0.1)
				(type default)
			)
			(layer "F.Fab")
		)
		(fp_line
			(start 0.12065 -0.2794)
			(end 0.12065 -0.3048)
			(stroke
				(width 0.1)
				(type default)
			)
			(layer "F.Fab")
		)
		(fp_line
			(start 0.12065 -0.3048)
			(end 0.67945 -0.3048)
			(stroke
				(width 0.1)
				(type default)
			)
			(layer "F.Fab")
		)
		(fp_line
			(start 0.67945 -0.3048)
			(end 0.67945 0.3048)
			(stroke
				(width 0.1)
				(type default)
			)
			(layer "F.Fab")
		)
		(fp_line
			(start -0.67945 -0.305054)
			(end -0.12065 -0.305054)
			(stroke
				(width 0.1)
				(type default)
			)
			(layer "F.Fab")
		)
		(fp_line
			(start -0.12065 -0.305054)
			(end -0.12065 -0.2794)
			(stroke
				(width 0.1)
				(type default)
			)
			(layer "F.Fab")
		)
		(pad "1" smd circle
			(at -0.40005 0 270)
			(size 0 0)
			(layers "F.Cu" "F.Mask" "F.Paste")
			(net "RST_SMB_PDB_N")
		)
		(pad "2" smd circle
			(at 0.40005 0 270)
			(size 0 0)
			(layers "F.Cu" "F.Mask" "F.Paste")
			(net "P3V3_AUX")
		)
	)
	(footprint ""
		(layer "F.Cu")
		(at 37.846 -132.588 180)
		(property "Reference" "R5601"
			(at 0 0 180)
			(layer "F.SilkS")
			(hide yes)
			(effects
				(font
					(size 1.27 1.27)
				)
			)
		)
		(property "Value" ""
			(at 0 0 180)
			(layer "F.Fab")
			(effects
				(font
					(size 1.27 1.27)
				)
			)
		)
		(duplicate_pad_numbers_are_jumpers no)
		(fp_line
			(start 0.7874 0.4064)
			(end -0.7874 0.4064)
			(stroke
				(width 0.1524)
				(type default)
			)
			(layer "F.SilkS")
		)
		(fp_line
			(start 0.7874 -0.4064)
			(end 0.7874 0.4064)
			(stroke
				(width 0.1524)
				(type default)
			)
			(layer "F.SilkS")
		)
		(fp_line
			(start -0.7874 0.4064)
			(end -0.7874 -0.4064)
			(stroke
				(width 0.1524)
				(type default)
			)
			(layer "F.SilkS")
		)
		(fp_line
			(start -0.7874 -0.4064)
			(end 0.7874 -0.4064)
			(stroke
				(width 0.1524)
				(type default)
			)
			(layer "F.SilkS")
		)
		(fp_line
			(start 0.67945 0.3048)
			(end 0.120396 0.3048)
			(stroke
				(width 0.1)
				(type default)
			)
			(layer "F.Fab")
		)
		(fp_line
			(start 0.67945 -0.3048)
			(end 0.67945 0.3048)
			(stroke
				(width 0.1)
				(type default)
			)
			(layer "F.Fab")
		)
		(fp_line
			(start 0.12065 -0.2794)
			(end 0.12065 -0.3048)
			(stroke
				(width 0.1)
				(type default)
			)
			(layer "F.Fab")
		)
		(fp_line
			(start 0.12065 -0.3048)
			(end 0.67945 -0.3048)
			(stroke
				(width 0.1)
				(type default)
			)
			(layer "F.Fab")
		)
		(fp_line
			(start 0.120396 0.3048)
			(end 0.120396 0.2794)
			(stroke
				(width 0.1)
				(type default)
			)
			(layer "F.Fab")
		)
		(fp_line
			(start 0.120396 0.2794)
			(end -0.12065 0.2794)
			(stroke
				(width 0.1)
				(type default)
			)
			(layer "F.Fab")
		)
		(fp_line
			(start -0.12065 0.3048)
			(end -0.67945 0.3048)
			(stroke
				(width 0.1)
				(type default)
			)
			(layer "F.Fab")
		)
		(fp_line
			(start -0.12065 0.2794)
			(end -0.12065 0.3048)
			(stroke
				(width 0.1)
				(type default)
			)
			(layer "F.Fab")
		)
		(fp_line
			(start -0.12065 -0.2794)
			(end 0.12065 -0.2794)
			(stroke
				(width 0.1)
				(type default)
			)
			(layer "F.Fab")
		)
		(fp_line
			(start -0.12065 -0.305054)
			(end -0.12065 -0.2794)
			(stroke
				(width 0.1)
				(type default)
			)
			(layer "F.Fab")
		)
		(fp_line
			(start -0.67945 0.3048)
			(end -0.67945 -0.305054)
			(stroke
				(width 0.1)
				(type default)
			)
			(layer "F.Fab")
		)
		(fp_line
			(start -0.67945 -0.305054)
			(end -0.12065 -0.305054)
			(stroke
				(width 0.1)
				(type default)
			)
			(layer "F.Fab")
		)
		(pad "1" smd rect
			(at -0.40005 0)
			(size 0.4572 0.508)
			(layers "F.Cu" "F.Mask" "F.Paste")
			(net "FAN_1_PWM")
		)
		(pad "2" smd rect
			(at 0.40005 0)
			(size 0.4572 0.508)
			(layers "F.Cu" "F.Mask" "F.Paste")
			(net "FAN_1_PWM_R1")
		)
	)
	(footprint ""
		(layer "F.Cu")
		(at 29.083 -141.605 -90)
		(property "Reference" "R5281"
			(at 0 0 270)
			(layer "F.SilkS")
			(hide yes)
			(effects
				(font
					(size 1.27 1.27)
				)
			)
		)
		(property "Value" ""
			(at 0 0 270)
			(layer "F.Fab")
			(effects
				(font
					(size 1.27 1.27)
				)
			)
		)
		(duplicate_pad_numbers_are_jumpers no)
		(fp_line
			(start -0.7874 0.4064)
			(end -0.7874 -0.4064)
			(stroke
				(width 0.1524)
				(type default)
			)
			(layer "F.SilkS")
		)
		(fp_line
			(start 0.7874 0.4064)
			(end -0.7874 0.4064)
			(stroke
				(width 0.1524)
				(type default)
			)
			(layer "F.SilkS")
		)
		(fp_line
			(start -0.7874 -0.4064)
			(end 0.7874 -0.4064)
			(stroke
				(width 0.1524)
				(type default)
			)
			(layer "F.SilkS")
		)
		(fp_line
			(start 0.7874 -0.4064)
			(end 0.7874 0.4064)
			(stroke
				(width 0.1524)
				(type default)
			)
			(layer "F.SilkS")
		)
		(fp_line
			(start -0.67945 0.3048)
			(end -0.67945 -0.305054)
			(stroke
				(width 0.1)
				(type default)
			)
			(layer "F.Fab")
		)
		(fp_line
			(start -0.12065 0.3048)
			(end -0.67945 0.3048)
			(stroke
				(width 0.1)
				(type default)
			)
			(layer "F.Fab")
		)
		(fp_line
			(start 0.120396 0.3048)
			(end 0.120396 0.2794)
			(stroke
				(width 0.1)
				(type default)
			)
			(layer "F.Fab")
		)
		(fp_line
			(start 0.67945 0.3048)
			(end 0.120396 0.3048)
			(stroke
				(width 0.1)
				(type default)
			)
			(layer "F.Fab")
		)
		(fp_line
			(start -0.12065 0.2794)
			(end -0.12065 0.3048)
			(stroke
				(width 0.1)
				(type default)
			)
			(layer "F.Fab")
		)
		(fp_line
			(start 0.120396 0.2794)
			(end -0.12065 0.2794)
			(stroke
				(width 0.1)
				(type default)
			)
			(layer "F.Fab")
		)
		(fp_line
			(start -0.12065 -0.2794)
			(end 0.12065 -0.2794)
			(stroke
				(width 0.1)
				(type default)
			)
			(layer "F.Fab")
		)
		(fp_line
			(start 0.12065 -0.2794)
			(end 0.12065 -0.3048)
			(stroke
				(width 0.1)
				(type default)
			)
			(layer "F.Fab")
		)
		(fp_line
			(start 0.12065 -0.3048)
			(end 0.67945 -0.3048)
			(stroke
				(width 0.1)
				(type default)
			)
			(layer "F.Fab")
		)
		(fp_line
			(start 0.67945 -0.3048)
			(end 0.67945 0.3048)
			(stroke
				(width 0.1)
				(type default)
			)
			(layer "F.Fab")
		)
		(fp_line
			(start -0.67945 -0.305054)
			(end -0.12065 -0.305054)
			(stroke
				(width 0.1)
				(type default)
			)
			(layer "F.Fab")
		)
		(fp_line
			(start -0.12065 -0.305054)
			(end -0.12065 -0.2794)
			(stroke
				(width 0.1)
				(type default)
			)
			(layer "F.Fab")
		)
		(pad "1" smd circle
			(at -0.40005 0 270)
			(size 0 0)
			(layers "F.Cu" "F.Mask" "F.Paste")
			(net "SMB_FAN2_R_SDA")
		)
		(pad "2" smd circle
			(at 0.40005 0 270)
			(size 0 0)
			(layers "F.Cu" "F.Mask" "F.Paste")
			(net "P3V3_AUX")
		)
	)
)
